# BASEBOARD_FAB2 (Tioga Pass) — schematic netlist excerpt (pin names and nets, part order shuffled) for the footprints in the layout excerpt that follows; sources: Cadence DE-HDL packaged netlist, KiCad conversion of Wiwynn_Tioga_Pass_MB.brd

C9P7  CAP  10UF 16V 10% X6S  pkg 0805  page 208 : A = VR_FET_SW_P12V_STBY_PVCCIN_CPU1 ; B = GND
R7G28  RES  1.00K 1% CHIP  pkg 0402  page 136 : A = PD_ME_RCVR_N ; B = GND
C2N8  CAP_A  1.0UF 6.3V 10% X6S  pkg 0402V  page 131 : A = P1V05_PCH_STBY ; B = GND

(kicad_pcb
	(version 20260206)
	(generator "pcbnew")
	(generator_version "10.0")
	(general
		(thickness 1.6)
		(legacy_teardrops no)
	)
	(paper "A4")
	(title_block
		(title "Wiwynn_Tioga_Pass_MB.brd")
		(comment 1 "Tioga Pass / footprints 2411-2413 of 4770")
	)
	(layers
		(0 "F.Cu" signal "TOP")
		(4 "In1.Cu" signal "L2GND")
		(6 "In2.Cu" signal "L3")
		(8 "In3.Cu" signal "L4GND")
		(10 "In4.Cu" signal "L5")
		(12 "In5.Cu" signal "L6GND")
		(14 "In6.Cu" signal "L7VCC")
		(16 "In7.Cu" signal "L8VCC")
		(18 "In8.Cu" signal "L9GND")
		(20 "In9.Cu" signal "L10")
		(22 "In10.Cu" signal "L11GND")
		(24 "In11.Cu" signal "L12")
		(26 "In12.Cu" signal "L13GND")
		(2 "B.Cu" signal "BOTTOM")
		(9 "F.Adhes" user "F.Adhesive")
		(11 "B.Adhes" user "B.Adhesive")
		(13 "F.Paste" user "Package Geometry/Pastemask Top")
		(15 "B.Paste" user "Package Geometry/Pastemask Bottom")
		(5 "F.SilkS" user "Ref Des/Silkscreen Top")
		(7 "B.SilkS" user "Ref Des/Silkscreen Bottom")
		(1 "F.Mask" user "Board Geometry/Soldermask Top")
		(3 "B.Mask" user "Board Geometry/Soldermask Bottom")
		(17 "Dwgs.User" user "User.Drawings")
		(19 "Cmts.User" user "User.Comments")
		(21 "Eco1.User" user "User.Eco1")
		(23 "Eco2.User" user "User.Eco2")
		(25 "Edge.Cuts" user "Board Geometry/Outline")
		(27 "Margin" user)
		(31 "F.CrtYd" user "Package Geometry/Place Bound Top")
		(29 "B.CrtYd" user "Package Geometry/Place Bound Bottom")
		(35 "F.Fab" user "Ref Des/Assembly Top")
		(33 "B.Fab" user "Ref Des/Assembly Bottom")
	)
	(footprint ""
		(layer "B.Cu")
		(at 32.832802 -72.902064 90)
		(property "Reference" "C9P7"
			(at 0 0 90)
			(layer "B.SilkS")
			(hide yes)
			(effects
				(font
					(size 1.27 1.27)
				)
				(justify mirror)
			)
		)
		(property "Value" ""
			(at 0 0 90)
			(layer "B.Fab")
			(effects
				(font
					(size 1.27 1.27)
				)
				(justify mirror)
			)
		)
		(duplicate_pad_numbers_are_jumpers no)
		(fp_poly
			(pts
				(xy 0.7239 -0.2159) (xy -0.7239 -0.2159) (xy -0.7239 1.9939) (xy 0.7239 1.9939)
			)
			(stroke
				(width 0)
				(type default)
			)
			(fill no)
			(layer "B.CrtYd")
		)
		(fp_line
			(start 0.7239 -0.2159)
			(end 0.7239 1.9939)
			(stroke
				(width 0.1)
				(type default)
			)
			(layer "B.Fab")
		)
		(fp_line
			(start -0.7239 -0.2159)
			(end 0.7239 -0.2159)
			(stroke
				(width 0.1)
				(type default)
			)
			(layer "B.Fab")
		)
		(fp_line
			(start 0.7239 1.9939)
			(end -0.7239 1.9939)
			(stroke
				(width 0.1)
				(type default)
			)
			(layer "B.Fab")
		)
		(fp_line
			(start -0.7239 1.9939)
			(end -0.7239 -0.2159)
			(stroke
				(width 0.1)
				(type default)
			)
			(layer "B.Fab")
		)
		(pad "1" smd rect
			(at 0 0 270)
			(size 1.27 1.016)
			(layers "B.Cu" "B.Mask" "B.Paste")
			(net "VR_FET_SW_P12V_STBY_PVCCIN_CPU1")
		)
		(pad "2" smd rect
			(at 0 1.778 270)
			(size 1.27 1.016)
			(layers "B.Cu" "B.Mask" "B.Paste")
			(net "GND")
		)
		(zone
			(layer "B.Cu")
			(hatch none 0.5)
			(connect_pads
				(clearance 0)
			)
			(min_thickness 0.25)
			(keepout
				(tracks not_allowed)
				(vias allowed)
				(pads allowed)
				(copperpour not_allowed)
				(footprints allowed)
			)
			(placement
				(enabled no)
				(sheetname "")
			)
			(fill
				(thermal_gap 0.5)
				(thermal_bridge_width 0.5)
				(island_removal_mode 0)
			)
			(polygon
				(pts
					(xy 33.340802 -73.537064) (xy 33.340802 -72.267064) (xy 34.102802 -72.267064) (xy 34.102802 -73.537064)
				)
			)
		)
	)
	(footprint ""
		(layer "B.Cu")
		(at 369.5954 -5.3467 180)
		(property "Reference" "R7G28"
			(at 0 0 0)
			(layer "B.SilkS")
			(hide yes)
			(effects
				(font
					(size 1.27 1.27)
				)
				(justify mirror)
			)
		)
		(property "Value" ""
			(at 0 0 0)
			(layer "B.Fab")
			(effects
				(font
					(size 1.27 1.27)
				)
				(justify mirror)
			)
		)
		(duplicate_pad_numbers_are_jumpers no)
		(fp_poly
			(pts
				(xy 0.2794 -0.1016) (xy -0.2794 -0.1016) (xy -0.2794 0.9906) (xy 0.2794 0.9906)
			)
			(stroke
				(width 0)
				(type default)
			)
			(fill no)
			(layer "B.CrtYd")
		)
		(fp_line
			(start 0.2794 0.9906)
			(end -0.2794 0.9906)
			(stroke
				(width 0.1)
				(type default)
			)
			(layer "B.Fab")
		)
		(fp_line
			(start 0.2794 -0.1016)
			(end 0.2794 0.9906)
			(stroke
				(width 0.1)
				(type default)
			)
			(layer "B.Fab")
		)
		(fp_line
			(start -0.2794 0.9906)
			(end -0.2794 -0.1016)
			(stroke
				(width 0.1)
				(type default)
			)
			(layer "B.Fab")
		)
		(fp_line
			(start -0.2794 -0.1016)
			(end 0.2794 -0.1016)
			(stroke
				(width 0.1)
				(type default)
			)
			(layer "B.Fab")
		)
		(pad "1" smd rect
			(at 0 0)
			(size 0.508 0.508)
			(layers "B.Cu" "B.Mask" "B.Paste")
			(net "PD_ME_RCVR_N")
		)
		(pad "2" smd rect
			(at 0 0.889)
			(size 0.508 0.508)
			(layers "B.Cu" "B.Mask" "B.Paste")
			(net "GND")
		)
		(zone
			(layer "B.Cu")
			(hatch none 0.5)
			(connect_pads
				(clearance 0)
			)
			(min_thickness 0.25)
			(keepout
				(tracks not_allowed)
				(vias allowed)
				(pads allowed)
				(copperpour not_allowed)
				(footprints allowed)
			)
			(placement
				(enabled no)
				(sheetname "")
			)
			(fill
				(thermal_gap 0.5)
				(thermal_bridge_width 0.5)
				(island_removal_mode 0)
			)
			(polygon
				(pts
					(xy 369.3414 -5.9817) (xy 369.8494 -5.9817) (xy 369.8494 -5.6007) (xy 369.3414 -5.6007)
				)
			)
		)
		(zone
			(layer "B.Cu")
			(hatch none 0.5)
			(connect_pads
				(clearance 0)
			)
			(min_thickness 0.25)
			(keepout
				(tracks allowed)
				(vias not_allowed)
				(pads allowed)
				(copperpour not_allowed)
				(footprints allowed)
			)
			(placement
				(enabled no)
				(sheetname "")
			)
			(fill
				(thermal_gap 0.5)
				(thermal_bridge_width 0.5)
				(island_removal_mode 0)
			)
			(polygon
				(pts
					(xy 369.3414 -5.6007) (xy 369.8494 -5.6007) (xy 369.8494 -5.9817) (xy 369.3414 -5.9817)
				)
			)
		)
	)
	(footprint ""
		(layer "B.Cu")
		(at 393.03325 -110.0328 -90)
		(property "Reference" "C2N8"
			(at 0 0 90)
			(layer "B.SilkS")
			(hide yes)
			(effects
				(font
					(size 1.27 1.27)
				)
				(justify mirror)
			)
		)
		(property "Value" ""
			(at 0 0 90)
			(layer "B.Fab")
			(effects
				(font
					(size 1.27 1.27)
				)
				(justify mirror)
			)
		)
		(duplicate_pad_numbers_are_jumpers no)
		(fp_rect
			(start 0.2794 0.9144)
			(end -0.2794 -0.1143)
			(stroke
				(width 0)
				(type default)
			)
			(fill no)
			(layer "B.CrtYd")
		)
		(fp_line
			(start -0.2794 0.9144)
			(end 0.2794 0.9144)
			(stroke
				(width 0.1)
				(type default)
			)
			(layer "B.Fab")
		)
		(fp_line
			(start 0.2794 0.9144)
			(end 0.2794 -0.1143)
			(stroke
				(width 0.1)
				(type default)
			)
			(layer "B.Fab")
		)
		(fp_line
			(start -0.2794 -0.1143)
			(end -0.2794 0.9144)
			(stroke
				(width 0.1)
				(type default)
			)
			(layer "B.Fab")
		)
		(fp_line
			(start 0.2794 -0.1143)
			(end -0.2794 -0.1143)
			(stroke
				(width 0.1)
				(type default)
			)
			(layer "B.Fab")
		)
		(pad "1" smd custom
			(at 0 0 180)
			(size 0.10414 0.10414)
			(layers "B.Cu" "B.Mask" "B.Paste")
			(net "P1V05_PCH_STBY")
			(options
				(clearance outline)
				(anchor circle)
			)
			(primitives
				(gr_poly
					(pts
						(xy -0.20828 -0.08636) (xy -0.20828 0.08636) (xy -0.08636 0.20828) (xy 0.086614 0.20828) (xy 0.20828 0.086614)
						(xy 0.20828 -0.08636) (xy 0.08636 -0.20828) (xy -0.08636 -0.20828)
					)
					(width 0)
					(fill yes)
				)
			)
		)
		(pad "2" smd custom
			(at 0 0.8001 180)
			(size 0.10414 0.10414)
			(layers "B.Cu" "B.Mask" "B.Paste")
			(net "GND")
			(options
				(clearance outline)
				(anchor circle)
			)
			(primitives
				(gr_poly
					(pts
						(xy -0.20828 -0.08636) (xy -0.20828 0.08636) (xy -0.08636 0.20828) (xy 0.086614 0.20828) (xy 0.20828 0.086614)
						(xy 0.20828 -0.08636) (xy 0.08636 -0.20828) (xy -0.08636 -0.20828)
					)
					(width 0)
					(fill yes)
				)
			)
		)
		(zone
			(layer "B.Cu")
			(hatch none 0.5)
			(connect_pads
				(clearance 0)
			)
			(min_thickness 0.25)
			(keepout
				(tracks not_allowed)
				(vias allowed)
				(pads allowed)
				(copperpour not_allowed)
				(footprints allowed)
			)
			(placement
				(enabled no)
				(sheetname "")
			)
			(fill
				(thermal_gap 0.5)
				(thermal_bridge_width 0.5)
				(island_removal_mode 0)
			)
			(polygon
				(pts
					(xy 392.8237 -109.94517) (xy 392.4427 -109.94517) (xy 392.4427 -110.12043) (xy 392.8237 -110.120684)
				)
			)
		)
		(zone
			(layer "B.Cu")
			(hatch none 0.5)
			(connect_pads
				(clearance 0)
			)
			(min_thickness 0.25)
			(keepout
				(tracks allowed)
				(vias not_allowed)
				(pads allowed)
				(copperpour not_allowed)
				(footprints allowed)
			)
			(placement
				(enabled no)
				(sheetname "")
			)
			(fill
				(thermal_gap 0.5)
				(thermal_bridge_width 0.5)
				(island_removal_mode 0)
			)
			(polygon
				(pts
					(xy 392.8237 -109.94517) (xy 392.4427 -109.94517) (xy 392.4427 -110.12043) (xy 392.8237 -110.120684)
				)
			)
		)
	)
)
